# T6G (Grand Teton) — schematic parts with pin connectivity, parts 8082–8082 of 8303; source: Cadence DE-HDL packaged netlist (pstxprt.dat, pstxnet.dat, pstchip.dat)

U26  GENOA_SP5  SOCKET6096_13568-001 IO  pkg SOCKET6096_93-4X120-45XA  page 37  (pins 2689-3024 of 6096)
  BY32  VDDCR_CPU1_BY32  POWER  = PVDDCR_CPU1_P1
  BY33  VDDCR_CPU1_BY33  POWER  = PVDDCR_CPU1_P1
  BY34  VSS_BY34  POWER  = GND
  BY35  P2_TXN3  OUT  = P5E_CPU1_P2_TX_DN<3>
  BY36  P2_TXP3  OUT  = P5E_CPU1_P2_TX_DP<3>
  BY37  VSS_BY37  POWER  = GND
  BY39  VSS_BY39  POWER  = GND
  BY40  \p0_rxp12||sata14_rxp\  IN  = P5E_CPU1_P0_RX_DP<12>
  BY41  \p0_rxn12||sata14_rxn\  IN  = P5E_CPU1_P0_RX_DN<12>
  BY42  VSS_BY42  POWER  = GND
  BY43  VDDCR_CPU1_BY43  POWER  = PVDDCR_CPU1_P1
  BY44  VDDCR_CPU1_BY44  POWER  = PVDDCR_CPU1_P1
  BY45  VSS_BY45  POWER  = GND
  BY46  VDDCR_CPU1_BY46  POWER  = PVDDCR_CPU1_P1
  BY47  VDDCR_CPU1_BY47  POWER  = PVDDCR_CPU1_P1
  BY48  VSS_BY48  POWER  = GND
  BY49  VDDCR_CPU1_BY49  POWER  = PVDDCR_CPU1_P1
  BY50  VDDCR_CPU1_BY50  POWER  = PVDDCR_CPU1_P1
  BY51  VSS_BY51  POWER  = GND
  BY52  VDDCR_CPU1_BY52  POWER  = PVDDCR_CPU1_P1
  BY53  VDDCR_CPU1_BY53  POWER  = PVDDCR_CPU1_P1
  BY54  VSS_BY54  POWER  = GND
  BY55  MCB_DQS_H4  BI  = M_C_CPU1_SB_DQS_DP<4>
  BY56  MCB_CHECK0  BI  = M_C_CPU1_SB_CB<0>
  BY57  VSS_BY57  POWER  = GND
  BY58  MDB_DQS_H4  BI  = M_D_CPU1_SB_DQS_DP<4>
  BY59  VSS_BY59  POWER  = GND
  BY60  MDB_CHECK0  BI  = M_D_CPU1_SB_CB<0>
  BY61  VSS_BY61  POWER  = GND
  BY62  MBB_DQS_H4  BI  = M_B_CPU1_SB_DQS_DP<4>
  BY63  MBB_CHECK0  BI  = M_B_CPU1_SB_CB<0>
  BY64  VSS_BY64  POWER  = GND
  BY65  MFB_DQS_H4  BI  = M_F_CPU1_SB_DQS_DP<4>
  BY66  VSS_BY66  POWER  = GND
  BY67  MFB_CHECK0  BI  = M_F_CPU1_SB_CB<0>
  BY68  VSS_BY68  POWER  = GND
  BY69  MEB_DQS_H4  BI  = M_E_CPU1_SB_DQS_DP<4>
  BY70  MEB_CHECK0  BI  = M_E_CPU1_SB_CB<0>
  BY71  VSS_BY71  POWER  = GND
  BY72  MAB_DQS_H4  BI  = M_A_CPU1_SB_DQS_DP<4>
  BY73  VSS_BY73  POWER  = GND
  BY74  MAB_CHECK0  BI  = M_A_CPU1_SB_CB<0>
  C1  VSS_C1  POWER  = GND
  C2  VDDCR_CPU0_SENSE  POWER  = VSENSE_PVDDCR_CPU0_P1_DP
  C3  VSS_SENSE_A  POWER  = VSENSE_VSS_SENSE_A_P1
  C4  VDDCR_SOC_C4  POWER  = PVDDCR_SOC_P1
  C5  VSS_C5  POWER  = GND
  C6  GPP_CLK02N  OUT  = CLK_100M_CPU1_CLK02_R_DN
  C7  \i3c1_scl||i2c1_scl||spd1_scl||agpio147\  BI  = I3C_1_SPD_DDRGL_CPU1_R_SCL
  C8  VSS_C8  POWER  = GND
  C9  GPP_CLK05N  OUT  = CLK_100M_CPU1_CLK05_R_DN
  C10  VSS_C10  POWER  = GND
  C11  VSS_C11  POWER  = GND
  C12  GPP_CLK04N  OUT  = CLK_100M_CPU1_CLK04_R_DN
  C13  VSS_C13  POWER  = GND
  C14  \agpio257||sgpio1_clk||clk_req01_l\  BI  = NC
  C15  VSS_C15  POWER  = GND
  C16  DBREQ_L  IN  = JTAG_CPU1_DBREQ_N
  C17  TDI  IN  = JTAG_CPU1_TDI
  C18  TDO  OUT  = JTAG_CPU1_R_TDO
  C19  SP5R1  OUT  = CPU1_SP5R1
  C20  VDDCR_CPU0_C20  POWER  = PVDDCR_CPU0_P1
  C21  VSS_C21  POWER  = GND
  C22  PCC0_L  IN  = FM_P1_PCC0_N
  C23  TEST4_CCD15  TRI  = NC
  C24  VSS_C24  POWER  = GND
  C25  USB00_TXP  OUT  = NC_CPU1_USB3_USB00_TXN
  C26  USB00_TXN  OUT  = NC_CPU1_USB3_USB00_TXP
  C27  VSS_C27  POWER  = GND
  C28  USB01_RXN  IN  = NC_CPU1_USB3_USB01_RXN
  C29  USB01_RXP  IN  = NC_CPU1_USB3_USB01_RXP
  C30  VSS_C30  POWER  = GND
  C31  RSVD_C31  TRI  = NC
  C32  AZ_BITCLK  OUT  = NC_CPU1_AZ_BITCLK
  C33  \az_sdin0||sw_mdata3\  OUT  = NC_CPU1_AZ_SDIN0
  C34  RSVD_C34  TRI  = NC
  C35  RSVD_C35  TRI  = NC
  C36  VSS_C36  POWER  = GND
  C40  VSS_C40  POWER  = GND
  C41  P5_TXP3  OUT  = P3E_CPU1_P5_TX_DP<1>
  C42  P5_TXN3  OUT  = P3E_CPU1_P5_TX_DN<1>
  C43  VSS_C43  POWER  = GND
  C44  P5_TXP2  OUT  = P3E_CPU1_P5_TX_DP<0>
  C45  P5_TXN2  OUT  = P3E_CPU1_P5_TX_DN<0>
  C46  VSS_C46  POWER  = GND
  C47  \wafl_txp1||p5_txp1\  OUT  = WAFL_CPU1_TX1_CPU0_RX0_DP
  C48  \wafl_txn1||p5_txn1\  OUT  = WAFL_CPU1_TX1_CPU0_RX0_DN
  C49  VSS_C49  POWER  = GND
  C50  \wafl_txp0||p5_txp0\  OUT  = NC
  C51  \wafl_txn0||p5_txn0\  OUT  = NC
  C52  VSS_C52  POWER  = GND
  C53  RSVD_C53  TRI  = NC
  C54  RSVD_C54  TRI  = NC
  C55  VSS_C55  POWER  = GND
  C56  VSS_C56  POWER  = GND
  C57  VSS_C57  POWER  = GND
  C58  TEST4_CCD12  TRI  = NC
  C59  TEST5_CCD12  TRI  = NC
  C60  TEST40  OUT  = TP_M_A_CPU1_SA_TEST40
  C61  VSS_C61  POWER  = GND
  C62  BP1  OUT  = CPU1_BP1
  C63  BP0  OUT  = CPU1_BP0
  C64  VSS_C64  POWER  = GND
  C65  XTRIG_L5  OUT  = CPU1_XTRIG_R2_L5
  C66  XTRIG_L4  OUT  = CPU1_XTRIG_R2_L4
  C67  VSS_C67  POWER  = GND
  C68  SP5R2  OUT  = CPU1_SP5R2
  C69  VSS_C69  POWER  = GND
  C70  CORETYPE0  OUT  = CPU1_CORETYPE0
  C71  VSS_C71  POWER  = GND
  C72  \i3c2_scl||i2c2_scl||spd2_scl||agpio149\  BI  = NC
  C73  VSS_C73  POWER  = GND
  C74  VDD_18_S5_SENSE  POWER  = VSENSE_PVDD18_S5_P1_DP
  C75  VSS_C75  POWER  = GND
  CA1  VSS_CA1  POWER  = GND
  CA2  MGB_CHECK2  BI  = M_G_CPU1_SB_CB<2>
  CA3  MGB_CHECK1  BI  = M_G_CPU1_SB_CB<1>
  CA4  VDD_11_S3_CA4  POWER  = PVDD11_S3_P1
  CA5  MKB_CHECK2  BI  = M_K_CPU1_SB_CB<2>
  CA6  VSS_CA6  POWER  = GND
  CA7  MKB_CHECK1  BI  = M_K_CPU1_SB_CB<1>
  CA8  VSS_CA8  POWER  = GND
  CA9  MLB_CHECK2  BI  = M_L_CPU1_SB_CB<2>
  CA10  MLB_CHECK1  BI  = M_L_CPU1_SB_CB<1>
  CA11  VDD_11_S3_CA11  POWER  = PVDD11_S3_P1
  CA12  MHB_CHECK2  BI  = M_H_CPU1_SB_CB<2>
  CA13  VSS_CA13  POWER  = GND
  CA14  MHB_CHECK1  BI  = M_H_CPU1_SB_CB<1>
  CA15  VSS_CA15  POWER  = GND
  CA16  MJB_CHECK2  BI  = M_J_CPU1_SB_CB<2>
  CA17  MJB_CHECK1  BI  = M_J_CPU1_SB_CB<1>
  CA18  VDD_11_S3_CA18  POWER  = PVDD11_S3_P1
  CA19  MIB_CHECK2  BI  = M_I_CPU1_SB_CB<2>
  CA20  VSS_CA20  POWER  = GND
  CA21  MIB_CHECK1  BI  = M_I_CPU1_SB_CB<1>
  CA22  VSS_CA22  POWER  = GND
  CA23  P2_TXN14  OUT  = P5E_CPU1_P2_TX_DN<14>
  CA24  P2_TXP14  OUT  = P5E_CPU1_P2_TX_DP<14>
  CA25  VSS_CA25  POWER  = GND
  CA26  P2_TXN11  OUT  = P5E_CPU1_P2_TX_DN<11>
  CA27  P2_TXP11  OUT  = P5E_CPU1_P2_TX_DP<11>
  CA28  VSS_CA28  POWER  = GND
  CA29  P2_TXN8  OUT  = P5E_CPU1_P2_TX_DN<8>
  CA30  P2_TXP8  OUT  = P5E_CPU1_P2_TX_DP<8>
  CA31  VSS_CA31  POWER  = GND
  CA32  P2_TXN5  OUT  = P5E_CPU1_P2_TX_DN<5>
  CA33  P2_TXP5  OUT  = P5E_CPU1_P2_TX_DP<5>
  CA34  VSS_CA34  POWER  = GND
  CA35  VSS_CA35  POWER  = GND
  CA36  VSS_CA36  POWER  = GND
  CA40  VSS_CA40  POWER  = GND
  CA41  VSS_CA41  POWER  = GND
  CA42  VSS_CA42  POWER  = GND
  CA43  \p0_rxp10||sata12_rxp\  IN  = P5E_CPU1_P0_RX_DP<10>
  CA44  \p0_rxn10||sata12_rxn\  IN  = P5E_CPU1_P0_RX_DN<10>
  CA45  VSS_CA45  POWER  = GND
  CA46  \p0_rxp7||sata07_rxp\  IN  = P5E_CPU1_P0_RX_DP<7>
  CA47  \p0_rxn7||sata07_rxn\  IN  = P5E_CPU1_P0_RX_DN<7>
  CA48  VSS_CA48  POWER  = GND
  CA49  \p0_rxp4||sata04_rxp\  IN  = P5E_CPU1_P0_RX_DP<4>
  CA50  \p0_rxn4||sata04_rxn\  IN  = P5E_CPU1_P0_RX_DN<4>
  CA51  VSS_CA51  POWER  = GND
  CA52  \p0_rxp1||sata01_rxp\  IN  = P5E_CPU1_P0_RX_DP<1>
  CA53  \p0_rxn1||sata01_rxn\  IN  = P5E_CPU1_P0_RX_DN<1>
  CA54  VSS_CA54  POWER  = GND
  CA55  MCB_CHECK1  BI  = M_C_CPU1_SB_CB<1>
  CA56  VSS_CA56  POWER  = GND
  CA57  MCB_CHECK2  BI  = M_C_CPU1_SB_CB<2>
  CA58  VDDIO_CA58  POWER  = PVDDIO_P1
  CA59  MDB_CHECK1  BI  = M_D_CPU1_SB_CB<1>
  CA60  MDB_CHECK2  BI  = M_D_CPU1_SB_CB<2>
  CA61  VSS_CA61  POWER  = GND
  CA62  MBB_CHECK1  BI  = M_B_CPU1_SB_CB<1>
  CA63  VSS_CA63  POWER  = GND
  CA64  MBB_CHECK2  BI  = M_B_CPU1_SB_CB<2>
  CA65  VDDIO_CA65  POWER  = PVDDIO_P1
  CA66  MFB_CHECK1  BI  = M_F_CPU1_SB_CB<1>
  CA67  MFB_CHECK2  BI  = M_F_CPU1_SB_CB<2>
  CA68  VSS_CA68  POWER  = GND
  CA69  MEB_CHECK1  BI  = M_E_CPU1_SB_CB<1>
  CA70  VSS_CA70  POWER  = GND
  CA71  MEB_CHECK2  BI  = M_E_CPU1_SB_CB<2>
  CA72  VDDIO_CA72  POWER  = PVDDIO_P1
  CA73  MAB_CHECK1  BI  = M_A_CPU1_SB_CB<1>
  CA74  MAB_CHECK2  BI  = M_A_CPU1_SB_CB<2>
  CA75  VSS_CA75  POWER  = GND
  CB2  MGB_DATA0  BI  = M_G_CPU1_SB_DQ<0>
  CB3  VSS_CB3  POWER  = GND
  CB4  MGB_CHECK3  BI  = M_G_CPU1_SB_CB<3>
  CB5  VSS_CB5  POWER  = GND
  CB6  MKB_DATA0  BI  = M_K_CPU1_SB_DQ<0>
  CB7  MKB_CHECK3  BI  = M_K_CPU1_SB_CB<3>
  CB8  VSS_CB8  POWER  = GND
  CB9  MLB_DATA0  BI  = M_L_CPU1_SB_DQ<0>
  CB10  VSS_CB10  POWER  = GND
  CB11  MLB_CHECK3  BI  = M_L_CPU1_SB_CB<3>
  CB12  VSS_CB12  POWER  = GND
  CB13  MHB_DATA0  BI  = M_H_CPU1_SB_DQ<0>
  CB14  MHB_CHECK3  BI  = M_H_CPU1_SB_CB<3>
  CB15  VSS_CB15  POWER  = GND
  CB16  MJB_DATA0  BI  = M_J_CPU1_SB_DQ<0>
  CB17  VSS_CB17  POWER  = GND
  CB18  MJB_CHECK3  BI  = M_J_CPU1_SB_CB<3>
  CB19  VSS_CB19  POWER  = GND
  CB20  MIB_DATA0  BI  = M_I_CPU1_SB_DQ<0>
  CB21  MIB_CHECK3  BI  = M_I_CPU1_SB_CB<3>
  CB22  VDD_11_S3_CB22  POWER  = PVDD11_S3_P1
  CB23  VSS_CB23  POWER  = GND
  CB24  VSS_CB24  POWER  = GND
  CB25  VSS_CB25  POWER  = GND
  CB26  VSS_CB26  POWER  = GND
  CB27  VSS_CB27  POWER  = GND
  CB28  VSS_CB28  POWER  = GND
  CB29  VSS_CB29  POWER  = GND
  CB30  VSS_CB30  POWER  = GND
  CB31  VSS_CB31  POWER  = GND
  CB32  VSS_CB32  POWER  = GND
  CB33  VSS_CB33  POWER  = GND
  CB34  VSS_CB34  POWER  = GND
  CB35  P2_TXN2  OUT  = P5E_CPU1_P2_TX_DN<2>
  CB36  P2_TXP2  OUT  = P5E_CPU1_P2_TX_DP<2>
  CB37  VSS_CB37  POWER  = GND
  CB39  VSS_CB39  POWER  = GND
  CB40  \p0_rxp13||sata15_rxp\  IN  = P5E_CPU1_P0_RX_DP<13>
  CB41  \p0_rxn13||sata15_rxn\  IN  = P5E_CPU1_P0_RX_DN<13>
  CB42  VSS_CB42  POWER  = GND
  CB43  VSS_CB43  POWER  = GND
  CB44  VSS_CB44  POWER  = GND
  CB45  VSS_CB45  POWER  = GND
  CB46  VSS_CB46  POWER  = GND
  CB47  VSS_CB47  POWER  = GND
  CB48  VSS_CB48  POWER  = GND
  CB49  VSS_CB49  POWER  = GND
  CB50  VSS_CB50  POWER  = GND
  CB51  VSS_CB51  POWER  = GND
  CB52  VSS_CB52  POWER  = GND
  CB53  VSS_CB53  POWER  = GND
  CB54  VDDIO_CB54  POWER  = PVDDIO_P1
  CB55  MCB_CHECK3  BI  = M_C_CPU1_SB_CB<3>
  CB56  MCB_DATA0  BI  = M_C_CPU1_SB_DQ<0>
  CB57  VSS_CB57  POWER  = GND
  CB58  MDB_CHECK3  BI  = M_D_CPU1_SB_CB<3>
  CB59  VSS_CB59  POWER  = GND
  CB60  MDB_DATA0  BI  = M_D_CPU1_SB_DQ<0>
  CB61  VSS_CB61  POWER  = GND
  CB62  MBB_CHECK3  BI  = M_B_CPU1_SB_CB<3>
  CB63  MBB_DATA0  BI  = M_B_CPU1_SB_DQ<0>
  CB64  VSS_CB64  POWER  = GND
  CB65  MFB_CHECK3  BI  = M_F_CPU1_SB_CB<3>
  CB66  VSS_CB66  POWER  = GND
  CB67  MFB_DATA0  BI  = M_F_CPU1_SB_DQ<0>
  CB68  VSS_CB68  POWER  = GND
  CB69  MEB_CHECK3  BI  = M_E_CPU1_SB_CB<3>
  CB70  MEB_DATA0  BI  = M_E_CPU1_SB_DQ<0>
  CB71  VSS_CB71  POWER  = GND
  CB72  MAB_CHECK3  BI  = M_A_CPU1_SB_CB<3>
  CB73  VSS_CB73  POWER  = GND
  CB74  MAB_DATA0  BI  = M_A_CPU1_SB_DQ<0>
  CC1  VSS_CC1  POWER  = GND
  CC2  MGB_DATA2  BI  = M_G_CPU1_SB_DQ<2>
  CC3  MGB_DATA1  BI  = M_G_CPU1_SB_DQ<1>
  CC4  VSS_CC4  POWER  = GND
  CC5  MKB_DATA2  BI  = M_K_CPU1_SB_DQ<2>
  CC6  VSS_CC6  POWER  = GND
  CC7  MKB_DATA1  BI  = M_K_CPU1_SB_DQ<1>
  CC8  VSS_CC8  POWER  = GND
  CC9  MLB_DATA2  BI  = M_L_CPU1_SB_DQ<2>
  CC10  MLB_DATA1  BI  = M_L_CPU1_SB_DQ<1>
  CC11  VSS_CC11  POWER  = GND
  CC12  MHB_DATA2  BI  = M_H_CPU1_SB_DQ<2>
  CC13  VSS_CC13  POWER  = GND
  CC14  MHB_DATA1  BI  = M_H_CPU1_SB_DQ<1>
  CC15  VSS_CC15  POWER  = GND
  CC16  MJB_DATA2  BI  = M_J_CPU1_SB_DQ<2>
  CC17  MJB_DATA1  BI  = M_J_CPU1_SB_DQ<1>
  CC18  VSS_CC18  POWER  = GND
  CC19  MIB_DATA2  BI  = M_I_CPU1_SB_DQ<2>
  CC20  VSS_CC20  POWER  = GND
  CC21  MIB_DATA1  BI  = M_I_CPU1_SB_DQ<1>
  CC22  VSS_CC22  POWER  = GND
  CC23  P3_TXN13  OUT  = P5E_CPU1_P3_TX_DN<13>
  CC24  P3_TXP13  OUT  = P5E_CPU1_P3_TX_DP<13>
  CC25  VSS_CC25  POWER  = GND
  CC26  P3_TXN10  OUT  = P5E_CPU1_P3_TX_DN<10>
  CC27  P3_TXP10  OUT  = P5E_CPU1_P3_TX_DP<10>
  CC28  VSS_CC28  POWER  = GND
  CC29  P3_TXN7  OUT  = P5E_CPU1_P3_TX_DN<7>
  CC30  P3_TXP7  OUT  = P5E_CPU1_P3_TX_DP<7>
  CC31  VSS_CC31  POWER  = GND
  CC32  P3_TXN3  OUT  = P5E_CPU1_P3_TX_DN<3>
  CC33  P3_TXP3  OUT  = P5E_CPU1_P3_TX_DP<3>
  CC34  VSS_CC34  POWER  = GND
  CC35  VDDCR_CPU1_CC35  POWER  = PVDDCR_CPU1_P1
  CC36  VDDCR_CPU1_CC36  POWER  = PVDDCR_CPU1_P1
  CC40  VDDCR_CPU1_CC40  POWER  = PVDDCR_CPU1_P1
  CC41  VDDCR_CPU1_CC41  POWER  = PVDDCR_CPU1_P1
  CC42  VSS_CC42  POWER  = GND
  CC43  P1_RXP12  IN  = P5E_CPU1_P1_RX_DP<12>
  CC44  P1_RXN12  IN  = P5E_CPU1_P1_RX_DN<12>
  CC45  VSS_CC45  POWER  = GND
  CC46  P1_RXP8  IN  = P5E_CPU1_P1_RX_DP<8>
  CC47  P1_RXN8  IN  = P5E_CPU1_P1_RX_DN<8>
  CC48  VSS_CC48  POWER  = GND
  CC49  P1_RXP5  IN  = P5E_CPU1_P1_RX_DP<5>
  CC50  P1_RXN5  IN  = P5E_CPU1_P1_RX_DN<5>
  CC51  VSS_CC51  POWER  = GND
  CC52  P1_RXP2  IN  = P5E_CPU1_P1_RX_DP<2>
  CC53  P1_RXN2  IN  = P5E_CPU1_P1_RX_DN<2>
  CC54  VSS_CC54  POWER  = GND
  CC55  MCB_DATA1  BI  = M_C_CPU1_SB_DQ<1>
  CC56  VSS_CC56  POWER  = GND
  CC57  MCB_DATA2  BI  = M_C_CPU1_SB_DQ<2>
  CC58  VSS_CC58  POWER  = GND
  CC59  MDB_DATA1  BI  = M_D_CPU1_SB_DQ<1>
  CC60  MDB_DATA2  BI  = M_D_CPU1_SB_DQ<2>
  CC61  VSS_CC61  POWER  = GND
  CC62  MBB_DATA1  BI  = M_B_CPU1_SB_DQ<1>
  CC63  VSS_CC63  POWER  = GND
  CC64  MBB_DATA2  BI  = M_B_CPU1_SB_DQ<2>
  CC65  VSS_CC65  POWER  = GND
  CC66  MFB_DATA1  BI  = M_F_CPU1_SB_DQ<1>
  CC67  MFB_DATA2  BI  = M_F_CPU1_SB_DQ<2>
  CC68  VSS_CC68  POWER  = GND
  CC69  MEB_DATA1  BI  = M_E_CPU1_SB_DQ<1>
  CC70  VSS_CC70  POWER  = GND
  CC71  MEB_DATA2  BI  = M_E_CPU1_SB_DQ<2>
  CC72  VSS_CC72  POWER  = GND
  CC73  MAB_DATA1  BI  = M_A_CPU1_SB_DQ<1>
  CC74  MAB_DATA2  BI  = M_A_CPU1_SB_DQ<2>
  CC75  VSS_CC75  POWER  = GND
  CD2  MGB_DQS_H0  BI  = M_G_CPU1_SB_DQS_DP<0>
  CD3  VSS_CD3  POWER  = GND
  CD4  MGB_DATA3  BI  = M_G_CPU1_SB_DQ<3>
  CD5  VDD_11_S3_CD5  POWER  = PVDD11_S3_P1
  CD6  MKB_DQS_H0  BI  = M_K_CPU1_SB_DQS_DP<0>
  CD7  MKB_DATA3  BI  = M_K_CPU1_SB_DQ<3>
